(kicad_pcb
	(version 20240108)
	(generator "pcbnew")
	(generator_version "8.0")
	(general
		(thickness 1.6)
		(legacy_teardrops no)
	)
	(paper "A4")
	(title_block
		(title "Jetson Orin Baseboard OCuLink Expansion")
		(date "2025-03-18")
		(rev "1.1.0")
		(company "Antmicro Ltd")
		(comment 1 "www.antmicro.com")
		(comment 9 "footprints 55-59 of 119")
	)
	(layers
		(0 "F.Cu" signal)
		(1 "In1.Cu" signal)
		(2 "In2.Cu" signal)
		(31 "B.Cu" signal)
		(32 "B.Adhes" user "B.Adhesive")
		(33 "F.Adhes" user "F.Adhesive")
		(34 "B.Paste" user)
		(35 "F.Paste" user)
		(36 "B.SilkS" user "B.Silkscreen")
		(37 "F.SilkS" user "F.Silkscreen")
		(38 "B.Mask" user)
		(39 "F.Mask" user)
		(40 "Dwgs.User" user "User.Drawings")
		(41 "Cmts.User" user "User.Comments")
		(42 "Eco1.User" user "User.Eco1")
		(43 "Eco2.User" user "User.Eco2")
		(44 "Edge.Cuts" user)
		(45 "Margin" user)
		(46 "B.CrtYd" user "B.Courtyard")
		(47 "F.CrtYd" user "F.Courtyard")
		(48 "B.Fab" user)
		(49 "F.Fab" user)
	)
	(footprint "antmicro-footprints:oshw-logo"
		(layer "F.Cu")
		(at 143.8 94.1 90)
		(descr "OSHW Logo")
		(tags "OSHW Logo")
		(property "Reference" "N3"
			(at 0 -4.4 90)
			(layer "F.SilkS")
			(hide yes)
			(effects
				(font
					(size 0.7 0.7)
					(thickness 0.15)
				)
				(justify left bottom)
			)
		)
		(property "Value" "oshw_logo"
			(at 0 -3.4 90)
			(layer "F.Fab")
			(hide yes)
			(effects
				(font
					(size 0.7 0.7)
					(thickness 0.15)
				)
				(justify left bottom)
			)
		)
		(property "Footprint" "antmicro-footprints:oshw-logo"
			(at 0 0 90)
			(layer "F.Fab")
			(hide yes)
			(effects
				(font
					(size 1.27 1.27)
					(thickness 0.15)
				)
			)
		)
		(property "Description" "Mechanical part"
			(at 0 0 90)
			(layer "F.Fab")
			(hide yes)
			(effects
				(font
					(size 1.27 1.27)
					(thickness 0.15)
				)
			)
		)
		(property "Author" "Antmicro"
			(at 0 0 90)
			(unlocked yes)
			(layer "F.Fab")
			(hide yes)
			(effects
				(font
					(size 1 1)
					(thickness 0.15)
				)
			)
		)
		(property "License" "Apache-2.0"
			(at 0 0 90)
			(unlocked yes)
			(layer "F.Fab")
			(hide yes)
			(effects
				(font
					(size 1 1)
					(thickness 0.15)
				)
			)
		)
		(property "MPN" ""
			(at 0 0 90)
			(unlocked yes)
			(layer "F.Fab")
			(hide yes)
			(effects
				(font
					(size 1 1)
					(thickness 0.15)
				)
			)
		)
		(property "Manufacturer" ""
			(at 0 0 90)
			(unlocked yes)
			(layer "F.Fab")
			(hide yes)
			(effects
				(font
					(size 1 1)
					(thickness 0.15)
				)
			)
		)
		(sheetname "Root")
		(sheetfile "jetson-orin-baseboard-oculink-expansion.kicad_sch")
		(attr exclude_from_pos_files exclude_from_bom allow_soldermask_bridges)
	)
	(footprint "antmicro-footprints:R_0402_1005Metric"
		(layer "B.Cu")
		(at 114.67 130.28 90)
		(descr "Resistor SMD 0402")
		(tags "resistor SMD 0402")
		(property "Reference" "R45"
			(at -2.95 -0.38 90)
			(layer "B.SilkS")
			(effects
				(font
					(size 0.7 0.7)
					(thickness 0.15)
				)
				(justify right top mirror)
			)
		)
		(property "Value" "R_0R_0402"
			(at -1.011843 -1.772047 90)
			(layer "B.Fab")
			(effects
				(font
					(size 0.7 0.7)
					(thickness 0.15)
				)
				(justify right top mirror)
			)
		)
		(property "Footprint" "antmicro-footprints:R_0402_1005Metric"
			(at 0 0 90)
			(layer "B.Fab")
			(hide yes)
			(effects
				(font
					(size 1.27 1.27)
					(thickness 0.15)
				)
				(justify mirror)
			)
		)
		(property "Datasheet" "https://industrial.panasonic.com/cdbs/www-data/pdf/RDA0000/AOA0000C301.pdf"
			(at 0 0 90)
			(layer "B.Fab")
			(hide yes)
			(effects
				(font
					(size 1.27 1.27)
					(thickness 0.15)
				)
				(justify mirror)
			)
		)
		(property "Description" "SMD Chip Resistor, Jumper, 0 ohm, 100 mW, 0402 [1005 Metric], Thick Film, General Purpose"
			(at 0 0 90)
			(layer "B.Fab")
			(hide yes)
			(effects
				(font
					(size 1.27 1.27)
					(thickness 0.15)
				)
				(justify mirror)
			)
		)
		(property "MPN" "ERJ2GE0R00X"
			(at 0 0 -90)
			(unlocked yes)
			(layer "B.Fab")
			(hide yes)
			(effects
				(font
					(size 1 1)
					(thickness 0.15)
				)
				(justify mirror)
			)
		)
		(property "Manufacturer" "Panasonic"
			(at 0 0 -90)
			(unlocked yes)
			(layer "B.Fab")
			(hide yes)
			(effects
				(font
					(size 1 1)
					(thickness 0.15)
				)
				(justify mirror)
			)
		)
		(property "License" "Apache-2.0"
			(at 0 0 -90)
			(unlocked yes)
			(layer "B.Fab")
			(hide yes)
			(effects
				(font
					(size 1 1)
					(thickness 0.15)
				)
				(justify mirror)
			)
		)
		(property "Author" "Antmicro"
			(at 0 0 -90)
			(unlocked yes)
			(layer "B.Fab")
			(hide yes)
			(effects
				(font
					(size 1 1)
					(thickness 0.15)
				)
				(justify mirror)
			)
		)
		(property "Val" "0R"
			(at 0 0 -90)
			(unlocked yes)
			(layer "B.Fab")
			(hide yes)
			(effects
				(font
					(size 1 1)
					(thickness 0.15)
				)
				(justify mirror)
			)
		)
		(property "Tolerance" ""
			(at 0 0 -90)
			(unlocked yes)
			(layer "B.Fab")
			(hide yes)
			(effects
				(font
					(size 1 1)
					(thickness 0.15)
				)
				(justify mirror)
			)
		)
		(property "Current" "1A"
			(at 0 0 -90)
			(unlocked yes)
			(layer "B.Fab")
			(hide yes)
			(effects
				(font
					(size 1 1)
					(thickness 0.15)
				)
				(justify mirror)
			)
		)
		(property "Public" "False"
			(at 0 0 -90)
			(unlocked yes)
			(layer "B.Fab")
			(hide yes)
			(effects
				(font
					(size 1 1)
					(thickness 0.15)
				)
				(justify mirror)
			)
		)
		(sheetname "Root")
		(sheetfile "jetson-orin-baseboard-oculink-expansion.kicad_sch")
		(attr smd dnp)
		(fp_rect
			(start -0.925 0.47)
			(end 0.925 -0.47)
			(stroke
				(width 0.05)
				(type default)
			)
			(fill none)
			(layer "B.CrtYd")
		)
		(fp_rect
			(start -0.5 0.25)
			(end 0.5 -0.25)
			(stroke
				(width 0.15)
				(type solid)
			)
			(fill none)
			(layer "B.Fab")
		)
		(fp_text user "Author: Antmicro"
			(at -0.95 -4.169 90)
			(layer "B.Fab")
			(hide yes)
			(effects
				(font
					(size 0.7 0.7)
					(thickness 0.15)
				)
				(justify right top mirror)
			)
		)
		(fp_text user "${REFERENCE}"
			(at -0.95 -3.168 90)
			(layer "B.Fab")
			(hide yes)
			(effects
				(font
					(size 0.7 0.7)
					(thickness 0.15)
				)
				(justify right top mirror)
			)
		)
		(fp_text user "License: Apache-2.0"
			(at -0.95 -5.169 90)
			(layer "B.Fab")
			(hide yes)
			(effects
				(font
					(size 0.7 0.7)
					(thickness 0.15)
				)
				(justify right top mirror)
			)
		)
		(pad "1" smd roundrect
			(at -0.48 0 90)
			(size 0.59 0.64)
			(layers "B.Cu" "B.Paste" "B.Mask")
			(roundrect_rratio 0.25)
			(net 64 "/I2C_SCL")
			(pintype "passive")
		)
		(pad "2" smd roundrect
			(at 0.48 0 90)
			(size 0.59 0.64)
			(layers "B.Cu" "B.Paste" "B.Mask")
			(roundrect_rratio 0.25)
			(net 108 "Net-(U3-SCL)")
			(pintype "passive")
		)
	)
	(footprint "antmicro-footprints:C_0402_1005Metric"
		(layer "B.Cu")
		(at 119.775 127.913 -90)
		(descr "Capacitor SMD 0402")
		(tags "capacitor SMD 0402")
		(property "Reference" "C25"
			(at 1.627 -0.445 90)
			(layer "B.SilkS")
			(effects
				(font
					(size 0.7 0.7)
					(thickness 0.15)
				)
				(justify left bottom mirror)
			)
		)
		(property "Value" "C_100n_0402"
			(at -1.022927 -2.155213 90)
			(layer "B.Fab")
			(effects
				(font
					(size 0.7 0.7)
					(thickness 0.15)
				)
				(justify left bottom mirror)
			)
		)
		(property "Footprint" "antmicro-footprints:C_0402_1005Metric"
			(at 0 0 90)
			(layer "B.Fab")
			(hide yes)
			(effects
				(font
					(size 1.27 1.27)
					(thickness 0.15)
				)
				(justify mirror)
			)
		)
		(property "Datasheet" "https://www.murata.com/products/productdetail?partno=GRM155R61H104KE14%23"
			(at 0 0 90)
			(layer "B.Fab")
			(hide yes)
			(effects
				(font
					(size 1.27 1.27)
					(thickness 0.15)
				)
				(justify mirror)
			)
		)
		(property "Description" "SMD Multilayer Ceramic Capacitor, 0.1 µF, 50 V, 0402 [1005 Metric], ± 10%, X5R, GRM Series"
			(at 0 0 90)
			(layer "B.Fab")
			(hide yes)
			(effects
				(font
					(size 1.27 1.27)
					(thickness 0.15)
				)
				(justify mirror)
			)
		)
		(property "MPN" "GRM155R61H104KE14D"
			(at 0 0 90)
			(unlocked yes)
			(layer "B.Fab")
			(hide yes)
			(effects
				(font
					(size 1 1)
					(thickness 0.15)
				)
				(justify mirror)
			)
		)
		(property "Manufacturer" "Murata"
			(at 0 0 90)
			(unlocked yes)
			(layer "B.Fab")
			(hide yes)
			(effects
				(font
					(size 1 1)
					(thickness 0.15)
				)
				(justify mirror)
			)
		)
		(property "License" "Apache-2.0"
			(at 0 0 90)
			(unlocked yes)
			(layer "B.Fab")
			(hide yes)
			(effects
				(font
					(size 1 1)
					(thickness 0.15)
				)
				(justify mirror)
			)
		)
		(property "Author" "Antmicro"
			(at 0 0 90)
			(unlocked yes)
			(layer "B.Fab")
			(hide yes)
			(effects
				(font
					(size 1 1)
					(thickness 0.15)
				)
				(justify mirror)
			)
		)
		(property "Val" "100n"
			(at 0 0 90)
			(unlocked yes)
			(layer "B.Fab")
			(hide yes)
			(effects
				(font
					(size 1 1)
					(thickness 0.15)
				)
				(justify mirror)
			)
		)
		(property "Voltage" "50V"
			(at 0 0 90)
			(unlocked yes)
			(layer "B.Fab")
			(hide yes)
			(effects
				(font
					(size 1 1)
					(thickness 0.15)
				)
				(justify mirror)
			)
		)
		(property "Dielectric" "X5R"
			(at 0 0 90)
			(unlocked yes)
			(layer "B.Fab")
			(hide yes)
			(effects
				(font
					(size 1 1)
					(thickness 0.15)
				)
				(justify mirror)
			)
		)
		(property "Public" "False"
			(at 0 0 90)
			(unlocked yes)
			(layer "B.Fab")
			(hide yes)
			(effects
				(font
					(size 1 1)
					(thickness 0.15)
				)
				(justify mirror)
			)
		)
		(sheetname "Root")
		(sheetfile "jetson-orin-baseboard-oculink-expansion.kicad_sch")
		(attr smd)
		(fp_rect
			(start -0.925 0.47)
			(end 0.925 -0.47)
			(stroke
				(width 0.05)
				(type default)
			)
			(fill none)
			(layer "B.CrtYd")
		)
		(fp_line
			(start -0.494 0.25)
			(end -0.494 -0.248)
			(stroke
				(width 0.15)
				(type solid)
			)
			(layer "B.Fab")
		)
		(fp_line
			(start 0.504 0.25)
			(end -0.494 0.25)
			(stroke
				(width 0.15)
				(type solid)
			)
			(layer "B.Fab")
		)
		(fp_line
			(start -0.494 -0.248)
			(end 0.504 -0.248)
			(stroke
				(width 0.15)
				(type solid)
			)
			(layer "B.Fab")
		)
		(fp_line
			(start 0.504 -0.248)
			(end 0.504 0.25)
			(stroke
				(width 0.15)
				(type solid)
			)
			(layer "B.Fab")
		)
		(fp_text user "Author: Antmicro"
			(at -0.939 -3.399 90)
			(layer "B.Fab")
			(hide yes)
			(effects
				(font
					(size 0.7 0.7)
					(thickness 0.15)
				)
				(justify left bottom mirror)
			)
		)
		(fp_text user "${REFERENCE}"
			(at -0.939 -4.599 90)
			(layer "B.Fab")
			(hide yes)
			(effects
				(font
					(size 0.7 0.7)
					(thickness 0.15)
				)
				(justify left bottom mirror)
			)
		)
		(fp_text user "License: Apache-2.0"
			(at -0.939 -5.799 90)
			(layer "B.Fab")
			(hide yes)
			(effects
				(font
					(size 0.7 0.7)
					(thickness 0.15)
				)
				(justify left bottom mirror)
			)
		)
		(pad "1" smd roundrect
			(at -0.48 0 270)
			(size 0.59 0.64)
			(layers "B.Cu" "B.Paste" "B.Mask")
			(roundrect_rratio 0.25)
			(net 51 "GND")
			(pintype "passive")
		)
		(pad "2" smd roundrect
			(at 0.48 0 270)
			(size 0.59 0.64)
			(layers "B.Cu" "B.Paste" "B.Mask")
			(roundrect_rratio 0.25)
			(net 23 "+3V3")
			(pintype "passive")
		)
	)
	(footprint "antmicro-footprints:R_0402_1005Metric"
		(layer "B.Cu")
		(at 115.776 126.834)
		(descr "Resistor SMD 0402")
		(tags "resistor SMD 0402")
		(property "Reference" "R40"
			(at -2.936 -0.364 0)
			(layer "B.SilkS")
			(effects
				(font
					(size 0.7 0.7)
					(thickness 0.15)
				)
				(justify right top mirror)
			)
		)
		(property "Value" "R_10k_0402"
			(at -1.011843 -1.772047 0)
			(layer "B.Fab")
			(effects
				(font
					(size 0.7 0.7)
					(thickness 0.15)
				)
				(justify right top mirror)
			)
		)
		(property "Footprint" "antmicro-footprints:R_0402_1005Metric"
			(at 0 0 0)
			(layer "B.Fab")
			(hide yes)
			(effects
				(font
					(size 1.27 1.27)
					(thickness 0.15)
				)
				(justify mirror)
			)
		)
		(property "Datasheet" "https://www.bourns.com/docs/product-datasheets/cr.pdf"
			(at 0 0 0)
			(layer "B.Fab")
			(hide yes)
			(effects
				(font
					(size 1.27 1.27)
					(thickness 0.15)
				)
				(justify mirror)
			)
		)
		(property "Description" "SMD Chip Resistor, 10 kohm, ± 1%, 62.5 mW, 0402 [1005 Metric], Thick Film, General Purpose"
			(at 0 0 0)
			(layer "B.Fab")
			(hide yes)
			(effects
				(font
					(size 1.27 1.27)
					(thickness 0.15)
				)
				(justify mirror)
			)
		)
		(property "MPN" "CR0402-FX-1002GLF"
			(at 0 0 180)
			(unlocked yes)
			(layer "B.Fab")
			(hide yes)
			(effects
				(font
					(size 1 1)
					(thickness 0.15)
				)
				(justify mirror)
			)
		)
		(property "Manufacturer" "Bourns"
			(at 0 0 180)
			(unlocked yes)
			(layer "B.Fab")
			(hide yes)
			(effects
				(font
					(size 1 1)
					(thickness 0.15)
				)
				(justify mirror)
			)
		)
		(property "License" "Apache-2.0"
			(at 0 0 180)
			(unlocked yes)
			(layer "B.Fab")
			(hide yes)
			(effects
				(font
					(size 1 1)
					(thickness 0.15)
				)
				(justify mirror)
			)
		)
		(property "Author" "Antmicro"
			(at 0 0 180)
			(unlocked yes)
			(layer "B.Fab")
			(hide yes)
			(effects
				(font
					(size 1 1)
					(thickness 0.15)
				)
				(justify mirror)
			)
		)
		(property "Val" "10k"
			(at 0 0 180)
			(unlocked yes)
			(layer "B.Fab")
			(hide yes)
			(effects
				(font
					(size 1 1)
					(thickness 0.15)
				)
				(justify mirror)
			)
		)
		(property "Tolerance" "1%"
			(at 0 0 180)
			(unlocked yes)
			(layer "B.Fab")
			(hide yes)
			(effects
				(font
					(size 1 1)
					(thickness 0.15)
				)
				(justify mirror)
			)
		)
		(sheetname "Root")
		(sheetfile "jetson-orin-baseboard-oculink-expansion.kicad_sch")
		(attr smd)
		(fp_rect
			(start -0.925 0.47)
			(end 0.925 -0.47)
			(stroke
				(width 0.05)
				(type default)
			)
			(fill none)
			(layer "B.CrtYd")
		)
		(fp_rect
			(start -0.5 0.25)
			(end 0.5 -0.25)
			(stroke
				(width 0.15)
				(type solid)
			)
			(fill none)
			(layer "B.Fab")
		)
		(fp_text user "${REFERENCE}"
			(at -0.95 -3.168 0)
			(layer "B.Fab")
			(hide yes)
			(effects
				(font
					(size 0.7 0.7)
					(thickness 0.15)
				)
				(justify right top mirror)
			)
		)
		(fp_text user "License: Apache-2.0"
			(at -0.95 -5.169 0)
			(layer "B.Fab")
			(hide yes)
			(effects
				(font
					(size 0.7 0.7)
					(thickness 0.15)
				)
				(justify right top mirror)
			)
		)
		(fp_text user "Author: Antmicro"
			(at -0.95 -4.169 0)
			(layer "B.Fab")
			(hide yes)
			(effects
				(font
					(size 0.7 0.7)
					(thickness 0.15)
				)
				(justify right top mirror)
			)
		)
		(pad "1" smd roundrect
			(at -0.48 0)
			(size 0.59 0.64)
			(layers "B.Cu" "B.Paste" "B.Mask")
			(roundrect_rratio 0.25)
			(net 108 "Net-(U3-SCL)")
			(pintype "passive")
		)
		(pad "2" smd roundrect
			(at 0.48 0)
			(size 0.59 0.64)
			(layers "B.Cu" "B.Paste" "B.Mask")
			(roundrect_rratio 0.25)
			(net 23 "+3V3")
			(pintype "passive")
		)
	)
	(footprint "antmicro-footprints:R_0402_1005Metric"
		(layer "B.Cu")
		(at 127.954 123.78775)
		(descr "Resistor SMD 0402")
		(tags "resistor SMD 0402")
		(property "Reference" "R29"
			(at -3.284 -0.37775 0)
			(layer "B.SilkS")
			(effects
				(font
					(size 0.7 0.7)
					(thickness 0.15)
				)
				(justify right top mirror)
			)
		)
		(property "Value" "R_1k_0402"
			(at -1.011843 -1.772047 0)
			(layer "B.Fab")
			(effects
				(font
					(size 0.7 0.7)
					(thickness 0.15)
				)
				(justify right top mirror)
			)
		)
		(property "Footprint" "antmicro-footprints:R_0402_1005Metric"
			(at 0 0 0)
			(layer "B.Fab")
			(hide yes)
			(effects
				(font
					(size 1.27 1.27)
					(thickness 0.15)
				)
				(justify mirror)
			)
		)
		(property "Datasheet" "https://www.bourns.com/docs/product-datasheets/cr.pdf"
			(at 0 0 0)
			(layer "B.Fab")
			(hide yes)
			(effects
				(font
					(size 1.27 1.27)
					(thickness 0.15)
				)
				(justify mirror)
			)
		)
		(property "Description" "SMD Chip Resistor, 1 kohm, ± 1%, 63 mW, 0402 [1005 Metric], Thick Film, General Purpose"
			(at 0 0 0)
			(layer "B.Fab")
			(hide yes)
			(effects
				(font
					(size 1.27 1.27)
					(thickness 0.15)
				)
				(justify mirror)
			)
		)
		(property "MPN" "CR0402-FX-1001GLF"
			(at 0 0 180)
			(unlocked yes)
			(layer "B.Fab")
			(hide yes)
			(effects
				(font
					(size 1 1)
					(thickness 0.15)
				)
				(justify mirror)
			)
		)
		(property "Manufacturer" "Bourns"
			(at 0 0 180)
			(unlocked yes)
			(layer "B.Fab")
			(hide yes)
			(effects
				(font
					(size 1 1)
					(thickness 0.15)
				)
				(justify mirror)
			)
		)
		(property "License" "Apache-2.0"
			(at 0 0 180)
			(unlocked yes)
			(layer "B.Fab")
			(hide yes)
			(effects
				(font
					(size 1 1)
					(thickness 0.15)
				)
				(justify mirror)
			)
		)
		(property "Author" "Antmicro"
			(at 0 0 180)
			(unlocked yes)
			(layer "B.Fab")
			(hide yes)
			(effects
				(font
					(size 1 1)
					(thickness 0.15)
				)
				(justify mirror)
			)
		)
		(property "Val" "1k"
			(at 0 0 180)
			(unlocked yes)
			(layer "B.Fab")
			(hide yes)
			(effects
				(font
					(size 1 1)
					(thickness 0.15)
				)
				(justify mirror)
			)
		)
		(property "Tolerance" "1%"
			(at 0 0 180)
			(unlocked yes)
			(layer "B.Fab")
			(hide yes)
			(effects
				(font
					(size 1 1)
					(thickness 0.15)
				)
				(justify mirror)
			)
		)
		(property "Public" "False"
			(at 0 0 180)
			(unlocked yes)
			(layer "B.Fab")
			(hide yes)
			(effects
				(font
					(size 1 1)
					(thickness 0.15)
				)
				(justify mirror)
			)
		)
		(sheetname "Root")
		(sheetfile "jetson-orin-baseboard-oculink-expansion.kicad_sch")
		(attr smd)
		(fp_rect
			(start -0.925 0.47)
			(end 0.925 -0.47)
			(stroke
				(width 0.05)
				(type default)
			)
			(fill none)
			(layer "B.CrtYd")
		)
		(fp_rect
			(start -0.5 0.25)
			(end 0.5 -0.25)
			(stroke
				(width 0.15)
				(type solid)
			)
			(fill none)
			(layer "B.Fab")
		)
		(fp_text user "License: Apache-2.0"
			(at -0.95 -5.169 0)
			(layer "B.Fab")
			(hide yes)
			(effects
				(font
					(size 0.7 0.7)
					(thickness 0.15)
				)
				(justify right top mirror)
			)
		)
		(fp_text user "${REFERENCE}"
			(at -0.95 -3.168 0)
			(layer "B.Fab")
			(hide yes)
			(effects
				(font
					(size 0.7 0.7)
					(thickness 0.15)
				)
				(justify right top mirror)
			)
		)
		(fp_text user "Author: Antmicro"
			(at -0.95 -4.169 0)
			(layer "B.Fab")
			(hide yes)
			(effects
				(font
					(size 0.7 0.7)
					(thickness 0.15)
				)
				(justify right top mirror)
			)
		)
		(pad "1" smd roundrect
			(at -0.48 0)
			(size 0.59 0.64)
			(layers "B.Cu" "B.Paste" "B.Mask")
			(roundrect_rratio 0.25)
			(net 23 "+3V3")
			(pintype "passive")
		)
		(pad "2" smd roundrect
			(at 0.48 0)
			(size 0.59 0.64)
			(layers "B.Cu" "B.Paste" "B.Mask")
			(roundrect_rratio 0.25)
			(net 102 "/TX_SW")
			(pintype "passive")
		)
	)
)
